(kicad_pcb
	(version 20260206)
	(generator "pcbnew")
	(generator_version "10.0")
	(general
		(thickness 1.6)
		(legacy_teardrops no)
	)
	(paper "A4")
	(title_block
		(title "03242023_DA0F0TMBIJ0_F0T_Motherboard_J_brd_V01_OCP.brd")
		(comment 1 "Grand Teton / footprints 5552-5556 of 6105")
	)
	(layers
		(0 "F.Cu" signal "TOP")
		(4 "In1.Cu" signal "GND")
		(6 "In2.Cu" signal "IN1")
		(8 "In3.Cu" signal "GND1")
		(10 "In4.Cu" signal "IN2")
		(12 "In5.Cu" signal "GND2")
		(14 "In6.Cu" signal "IN3")
		(16 "In7.Cu" signal "GND3")
		(18 "In8.Cu" signal "VCC")
		(20 "In9.Cu" signal "VCC1")
		(22 "In10.Cu" signal "GND4")
		(24 "In11.Cu" signal "IN4")
		(26 "In12.Cu" signal "GND5")
		(28 "In13.Cu" signal "IN5")
		(30 "In14.Cu" signal "GND6")
		(32 "In15.Cu" signal "IN6")
		(34 "In16.Cu" signal "GND7")
		(2 "B.Cu" signal "BOTTOM")
		(9 "F.Adhes" user "F.Adhesive")
		(11 "B.Adhes" user "B.Adhesive")
		(13 "F.Paste" user "Package Geometry/Pastemask Top")
		(15 "B.Paste" user "Package Geometry/Pastemask Bottom")
		(5 "F.SilkS" user "Ref Des/Silkscreen Top")
		(7 "B.SilkS" user "Ref Des/Silkscreen Bottom")
		(1 "F.Mask" user "Board Geometry/Soldermask Top")
		(3 "B.Mask" user "Board Geometry/Soldermask Bottom")
		(17 "Dwgs.User" user "User.Drawings")
		(19 "Cmts.User" user "User.Comments")
		(21 "Eco1.User" user "User.Eco1")
		(23 "Eco2.User" user "User.Eco2")
		(25 "Edge.Cuts" user "Board Geometry/Outline")
		(27 "Margin" user)
		(31 "F.CrtYd" user "Package Geometry/Place Bound Top")
		(29 "B.CrtYd" user "Package Geometry/Place Bound Bottom")
		(35 "F.Fab" user "Ref Des/Assembly Top")
		(33 "B.Fab" user "Ref Des/Assembly Bottom")
	)
	(footprint ""
		(layer "B.Cu")
		(at 134.633208 -333.782924 -90)
		(property "Reference" "PC495_P1_8"
			(at 0 0 90)
			(layer "B.SilkS")
			(hide yes)
			(effects
				(font
					(size 1.27 1.27)
				)
				(justify mirror)
			)
		)
		(property "Value" ""
			(at 0 0 90)
			(layer "B.Fab")
			(effects
				(font
					(size 1.27 1.27)
				)
				(justify mirror)
			)
		)
		(duplicate_pad_numbers_are_jumpers no)
		(fp_line
			(start -0.7874 0.4064)
			(end 0.7874 0.4064)
			(stroke
				(width 0.1524)
				(type default)
			)
			(layer "B.SilkS")
		)
		(fp_line
			(start 0.7874 0.4064)
			(end 0.7874 -0.4064)
			(stroke
				(width 0.1524)
				(type default)
			)
			(layer "B.SilkS")
		)
		(fp_line
			(start -0.7874 -0.4064)
			(end -0.7874 0.4064)
			(stroke
				(width 0.1524)
				(type default)
			)
			(layer "B.SilkS")
		)
		(fp_line
			(start 0.7874 -0.4064)
			(end -0.7874 -0.4064)
			(stroke
				(width 0.1524)
				(type default)
			)
			(layer "B.SilkS")
		)
		(fp_line
			(start -0.67945 0.3048)
			(end -0.120396 0.3048)
			(stroke
				(width 0.1)
				(type default)
			)
			(layer "B.Fab")
		)
		(fp_line
			(start -0.120396 0.3048)
			(end -0.120396 0.2794)
			(stroke
				(width 0.1)
				(type default)
			)
			(layer "B.Fab")
		)
		(fp_line
			(start 0.12065 0.3048)
			(end 0.67945 0.3048)
			(stroke
				(width 0.1)
				(type default)
			)
			(layer "B.Fab")
		)
		(fp_line
			(start 0.67945 0.3048)
			(end 0.67945 -0.305054)
			(stroke
				(width 0.1)
				(type default)
			)
			(layer "B.Fab")
		)
		(fp_line
			(start -0.120396 0.2794)
			(end 0.12065 0.2794)
			(stroke
				(width 0.1)
				(type default)
			)
			(layer "B.Fab")
		)
		(fp_line
			(start 0.12065 0.2794)
			(end 0.12065 0.3048)
			(stroke
				(width 0.1)
				(type default)
			)
			(layer "B.Fab")
		)
		(fp_line
			(start -0.12065 -0.2794)
			(end -0.12065 -0.3048)
			(stroke
				(width 0.1)
				(type default)
			)
			(layer "B.Fab")
		)
		(fp_line
			(start 0.12065 -0.2794)
			(end -0.12065 -0.2794)
			(stroke
				(width 0.1)
				(type default)
			)
			(layer "B.Fab")
		)
		(fp_line
			(start -0.67945 -0.3048)
			(end -0.67945 0.3048)
			(stroke
				(width 0.1)
				(type default)
			)
			(layer "B.Fab")
		)
		(fp_line
			(start -0.12065 -0.3048)
			(end -0.67945 -0.3048)
			(stroke
				(width 0.1)
				(type default)
			)
			(layer "B.Fab")
		)
		(fp_line
			(start 0.12065 -0.305054)
			(end 0.12065 -0.2794)
			(stroke
				(width 0.1)
				(type default)
			)
			(layer "B.Fab")
		)
		(fp_line
			(start 0.67945 -0.305054)
			(end 0.12065 -0.305054)
			(stroke
				(width 0.1)
				(type default)
			)
			(layer "B.Fab")
		)
		(pad "1" smd circle
			(at 0.40005 0 90)
			(size 0 0)
			(layers "B.Cu" "B.Mask" "B.Paste")
			(net "PVCCIN_CPU1")
		)
		(pad "2" smd circle
			(at -0.40005 0 90)
			(size 0 0)
			(layers "B.Cu" "B.Mask" "B.Paste")
			(net "GND")
		)
	)
	(footprint ""
		(layer "B.Cu")
		(at 168.83888 -103.723948)
		(property "Reference" "C1945"
			(at 0 0 0)
			(layer "B.SilkS")
			(hide yes)
			(effects
				(font
					(size 1.27 1.27)
				)
				(justify mirror)
			)
		)
		(property "Value" ""
			(at 0 0 0)
			(layer "B.Fab")
			(effects
				(font
					(size 1.27 1.27)
				)
				(justify mirror)
			)
		)
		(duplicate_pad_numbers_are_jumpers no)
		(fp_line
			(start -0.7874 -0.4064)
			(end -0.7874 0.4064)
			(stroke
				(width 0.1524)
				(type default)
			)
			(layer "B.SilkS")
		)
		(fp_line
			(start -0.7874 0.4064)
			(end 0.7874 0.4064)
			(stroke
				(width 0.1524)
				(type default)
			)
			(layer "B.SilkS")
		)
		(fp_line
			(start 0.7874 -0.4064)
			(end -0.7874 -0.4064)
			(stroke
				(width 0.1524)
				(type default)
			)
			(layer "B.SilkS")
		)
		(fp_line
			(start 0.7874 0.4064)
			(end 0.7874 -0.4064)
			(stroke
				(width 0.1524)
				(type default)
			)
			(layer "B.SilkS")
		)
		(fp_line
			(start -0.67945 -0.3048)
			(end -0.67945 0.3048)
			(stroke
				(width 0.1)
				(type default)
			)
			(layer "B.Fab")
		)
		(fp_line
			(start -0.67945 0.3048)
			(end -0.120396 0.3048)
			(stroke
				(width 0.1)
				(type default)
			)
			(layer "B.Fab")
		)
		(fp_line
			(start -0.12065 -0.3048)
			(end -0.67945 -0.3048)
			(stroke
				(width 0.1)
				(type default)
			)
			(layer "B.Fab")
		)
		(fp_line
			(start -0.12065 -0.2794)
			(end -0.12065 -0.3048)
			(stroke
				(width 0.1)
				(type default)
			)
			(layer "B.Fab")
		)
		(fp_line
			(start -0.120396 0.2794)
			(end 0.12065 0.2794)
			(stroke
				(width 0.1)
				(type default)
			)
			(layer "B.Fab")
		)
		(fp_line
			(start -0.120396 0.3048)
			(end -0.120396 0.2794)
			(stroke
				(width 0.1)
				(type default)
			)
			(layer "B.Fab")
		)
		(fp_line
			(start 0.12065 -0.305054)
			(end 0.12065 -0.2794)
			(stroke
				(width 0.1)
				(type default)
			)
			(layer "B.Fab")
		)
		(fp_line
			(start 0.12065 -0.2794)
			(end -0.12065 -0.2794)
			(stroke
				(width 0.1)
				(type default)
			)
			(layer "B.Fab")
		)
		(fp_line
			(start 0.12065 0.2794)
			(end 0.12065 0.3048)
			(stroke
				(width 0.1)
				(type default)
			)
			(layer "B.Fab")
		)
		(fp_line
			(start 0.12065 0.3048)
			(end 0.67945 0.3048)
			(stroke
				(width 0.1)
				(type default)
			)
			(layer "B.Fab")
		)
		(fp_line
			(start 0.67945 -0.305054)
			(end 0.12065 -0.305054)
			(stroke
				(width 0.1)
				(type default)
			)
			(layer "B.Fab")
		)
		(fp_line
			(start 0.67945 0.3048)
			(end 0.67945 -0.305054)
			(stroke
				(width 0.1)
				(type default)
			)
			(layer "B.Fab")
		)
		(pad "1" smd circle
			(at 0.40005 0 180)
			(size 0 0)
			(layers "B.Cu" "B.Mask" "B.Paste")
			(net "P3V3_AUX_FPGA_VCCIO0")
		)
		(pad "2" smd circle
			(at -0.40005 0 180)
			(size 0 0)
			(layers "B.Cu" "B.Mask" "B.Paste")
			(net "GND")
		)
	)
	(footprint ""
		(layer "B.Cu")
		(at 479.84537 -116.560092 -90)
		(property "Reference" "X39"
			(at -0.279908 -2.21996 270)
			(unlocked yes)
			(layer "B.SilkS")
			(effects
				(font
					(size 0.7874 0.5842)
					(thickness 0.1524)
				)
				(justify left mirror)
			)
		)
		(property "Value" ""
			(at 0 0 90)
			(layer "B.Fab")
			(effects
				(font
					(size 1.27 1.27)
				)
				(justify mirror)
			)
		)
		(property "Device Type" "TP_TDR_4P_FTS_TH-TP_TDR_4P_DIPA"
			(at -1.30175 1.27 180)
			(unlocked yes)
			(layer "B.Fab")
			(hide yes)
			(effects
				(font
					(size 0.635 0.4064)
					(thickness 0.1524)
				)
				(justify mirror)
			)
		)
		(property "User Part Number" "N_A"
			(at -1.30175 1.27 180)
			(unlocked yes)
			(layer "Cmts.User")
			(hide yes)
			(effects
				(font
					(size 0.635 0.4064)
					(thickness 0.1524)
				)
				(justify mirror)
			)
		)
		(duplicate_pad_numbers_are_jumpers no)
		(fp_line
			(start -2.54 3.81)
			(end -2.54 3.6703)
			(stroke
				(width 0.1524)
				(type default)
			)
			(layer "B.SilkS")
		)
		(fp_line
			(start 0 3.81)
			(end -2.54 3.81)
			(stroke
				(width 0.1524)
				(type default)
			)
			(layer "B.SilkS")
		)
		(fp_line
			(start 0 3.175)
			(end 0 3.81)
			(stroke
				(width 0.1524)
				(type default)
			)
			(layer "B.SilkS")
		)
		(fp_line
			(start -2.54 1.4097)
			(end -2.54 1.1303)
			(stroke
				(width 0.1524)
				(type default)
			)
			(layer "B.SilkS")
		)
		(fp_line
			(start 0 0.635)
			(end 0 1.905)
			(stroke
				(width 0.1524)
				(type default)
			)
			(layer "B.SilkS")
		)
		(fp_line
			(start -2.54 -1.1303)
			(end -2.54 -1.27)
			(stroke
				(width 0.1524)
				(type default)
			)
			(layer "B.SilkS")
		)
		(fp_line
			(start -2.54 -1.27)
			(end 0 -1.27)
			(stroke
				(width 0.1524)
				(type default)
			)
			(layer "B.SilkS")
		)
		(fp_line
			(start 0 -1.27)
			(end 0 -0.635)
			(stroke
				(width 0.1524)
				(type default)
			)
			(layer "B.SilkS")
		)
		(fp_poly
			(pts
				(xy 0.761746 0) (xy 2.285746 -0.762) (xy 2.285746 0.762)
			)
			(stroke
				(width 0)
				(type default)
			)
			(fill yes)
			(layer "B.SilkS")
		)
		(fp_line
			(start -2.54 3.81)
			(end -2.54 -1.27)
			(stroke
				(width 0.1)
				(type default)
			)
			(layer "B.Fab")
		)
		(fp_line
			(start 0 3.81)
			(end -2.54 3.81)
			(stroke
				(width 0.1)
				(type default)
			)
			(layer "B.Fab")
		)
		(fp_line
			(start -2.54 -1.27)
			(end 0 -1.27)
			(stroke
				(width 0.1)
				(type default)
			)
			(layer "B.Fab")
		)
		(fp_line
			(start 0 -1.27)
			(end 0 3.81)
			(stroke
				(width 0.1)
				(type default)
			)
			(layer "B.Fab")
		)
		(fp_poly
			(pts
				(xy 0.761746 0) (xy 2.285746 -0.762) (xy 2.285746 0.762)
			)
			(stroke
				(width 0)
				(type default)
			)
			(fill yes)
			(layer "B.Fab")
		)
		(pad "1" thru_hole circle
			(at 0 0 90)
			(size 1.0033 1.0033)
			(drill 0.249936)
			(layers "*.Cu" "*.Mask")
			(remove_unused_layers no)
			(net "TDR_DIFF_85_NECK_IN6_DP")
			(clearance 0.10795)
			(padstack
				(mode front_inner_back)
				(layer "Inner"
					(shape circle)
					(size 0.8001 0.8001)
					(clearance 0.1524)
				)
				(layer "B.Cu"
					(shape circle)
					(size 1.0033 1.0033)
					(thermal_gap 0.10795)
					(clearance 0.10795)
				)
			)
		)
		(pad "2" thru_hole circle
			(at -2.54 0 90)
			(size 1.9939 1.9939)
			(drill 0.249936)
			(layers "*.Cu" "*.Mask")
			(remove_unused_layers no)
			(net "T1_GND")
			(clearance 0.10795)
			(padstack
				(mode front_inner_back)
				(layer "Inner"
					(shape circle)
					(size 0.8001 0.8001)
					(clearance 0.1524)
				)
				(layer "B.Cu"
					(shape circle)
					(size 1.9939 1.9939)
					(thermal_gap 0.10795)
					(clearance 0.10795)
				)
			)
		)
		(pad "3" thru_hole circle
			(at -2.54 2.54 90)
			(size 1.9939 1.9939)
			(drill 0.249936)
			(layers "*.Cu" "*.Mask")
			(remove_unused_layers no)
			(net "T1_GND")
			(clearance 0.10795)
			(padstack
				(mode front_inner_back)
				(layer "Inner"
					(shape circle)
					(size 0.8001 0.8001)
					(clearance 0.1524)
				)
				(layer "B.Cu"
					(shape circle)
					(size 1.9939 1.9939)
					(thermal_gap 0.10795)
					(clearance 0.10795)
				)
			)
		)
		(pad "4" thru_hole circle
			(at 0 2.54 90)
			(size 1.0033 1.0033)
			(drill 0.249936)
			(layers "*.Cu" "*.Mask")
			(remove_unused_layers no)
			(net "TDR_DIFF_85_NECK_IN6_DN")
			(clearance 0.10795)
			(padstack
				(mode front_inner_back)
				(layer "Inner"
					(shape circle)
					(size 0.8001 0.8001)
					(clearance 0.1524)
				)
				(layer "B.Cu"
					(shape circle)
					(size 1.0033 1.0033)
					(thermal_gap 0.10795)
					(clearance 0.10795)
				)
			)
		)
	)
	(footprint ""
		(layer "B.Cu")
		(at 297.852846 -318.988948 90)
		(property "Reference" "R880"
			(at 0 0 90)
			(layer "B.SilkS")
			(hide yes)
			(effects
				(font
					(size 1.27 1.27)
				)
				(justify mirror)
			)
		)
		(property "Value" ""
			(at 0 0 90)
			(layer "B.Fab")
			(effects
				(font
					(size 1.27 1.27)
				)
				(justify mirror)
			)
		)
		(duplicate_pad_numbers_are_jumpers no)
		(fp_line
			(start 0.7874 -0.4064)
			(end -0.7874 -0.4064)
			(stroke
				(width 0.1524)
				(type default)
			)
			(layer "B.SilkS")
		)
		(fp_line
			(start -0.7874 -0.4064)
			(end -0.7874 0.4064)
			(stroke
				(width 0.1524)
				(type default)
			)
			(layer "B.SilkS")
		)
		(fp_line
			(start 0.7874 0.4064)
			(end 0.7874 -0.4064)
			(stroke
				(width 0.1524)
				(type default)
			)
			(layer "B.SilkS")
		)
		(fp_line
			(start -0.7874 0.4064)
			(end 0.7874 0.4064)
			(stroke
				(width 0.1524)
				(type default)
			)
			(layer "B.SilkS")
		)
		(fp_line
			(start 0.67945 -0.305054)
			(end 0.12065 -0.305054)
			(stroke
				(width 0.1)
				(type default)
			)
			(layer "B.Fab")
		)
		(fp_line
			(start 0.12065 -0.305054)
			(end 0.12065 -0.2794)
			(stroke
				(width 0.1)
				(type default)
			)
			(layer "B.Fab")
		)
		(fp_line
			(start -0.12065 -0.3048)
			(end -0.67945 -0.3048)
			(stroke
				(width 0.1)
				(type default)
			)
			(layer "B.Fab")
		)
		(fp_line
			(start -0.67945 -0.3048)
			(end -0.67945 0.3048)
			(stroke
				(width 0.1)
				(type default)
			)
			(layer "B.Fab")
		)
		(fp_line
			(start 0.12065 -0.2794)
			(end -0.12065 -0.2794)
			(stroke
				(width 0.1)
				(type default)
			)
			(layer "B.Fab")
		)
		(fp_line
			(start -0.12065 -0.2794)
			(end -0.12065 -0.3048)
			(stroke
				(width 0.1)
				(type default)
			)
			(layer "B.Fab")
		)
		(fp_line
			(start 0.12065 0.2794)
			(end 0.12065 0.3048)
			(stroke
				(width 0.1)
				(type default)
			)
			(layer "B.Fab")
		)
		(fp_line
			(start -0.120396 0.2794)
			(end 0.12065 0.2794)
			(stroke
				(width 0.1)
				(type default)
			)
			(layer "B.Fab")
		)
		(fp_line
			(start 0.67945 0.3048)
			(end 0.67945 -0.305054)
			(stroke
				(width 0.1)
				(type default)
			)
			(layer "B.Fab")
		)
		(fp_line
			(start 0.12065 0.3048)
			(end 0.67945 0.3048)
			(stroke
				(width 0.1)
				(type default)
			)
			(layer "B.Fab")
		)
		(fp_line
			(start -0.120396 0.3048)
			(end -0.120396 0.2794)
			(stroke
				(width 0.1)
				(type default)
			)
			(layer "B.Fab")
		)
		(fp_line
			(start -0.67945 0.3048)
			(end -0.120396 0.3048)
			(stroke
				(width 0.1)
				(type default)
			)
			(layer "B.Fab")
		)
		(pad "1" smd circle
			(at 0.40005 0 270)
			(size 0 0)
			(layers "B.Cu" "B.Mask" "B.Paste")
			(net "PWRGD_CHB_CPU0_DIMM2")
		)
		(pad "2" smd circle
			(at -0.40005 0 270)
			(size 0 0)
			(layers "B.Cu" "B.Mask" "B.Paste")
			(net "PWRGD_FAIL_CPU0_AB")
		)
	)
	(footprint ""
		(layer "B.Cu")
		(at 318.223138 -187.90793 -90)
		(property "Reference" "R239"
			(at 0 0 90)
			(layer "B.SilkS")
			(hide yes)
			(effects
				(font
					(size 1.27 1.27)
				)
				(justify mirror)
			)
		)
		(property "Value" ""
			(at 0 0 90)
			(layer "B.Fab")
			(effects
				(font
					(size 1.27 1.27)
				)
				(justify mirror)
			)
		)
		(duplicate_pad_numbers_are_jumpers no)
		(fp_line
			(start -0.7874 0.4064)
			(end 0.7874 0.4064)
			(stroke
				(width 0.1524)
				(type default)
			)
			(layer "B.SilkS")
		)
		(fp_line
			(start 0.7874 0.4064)
			(end 0.7874 -0.4064)
			(stroke
				(width 0.1524)
				(type default)
			)
			(layer "B.SilkS")
		)
		(fp_line
			(start -0.7874 -0.4064)
			(end -0.7874 0.4064)
			(stroke
				(width 0.1524)
				(type default)
			)
			(layer "B.SilkS")
		)
		(fp_line
			(start 0.7874 -0.4064)
			(end -0.7874 -0.4064)
			(stroke
				(width 0.1524)
				(type default)
			)
			(layer "B.SilkS")
		)
		(fp_line
			(start -0.67945 0.3048)
			(end -0.120396 0.3048)
			(stroke
				(width 0.1)
				(type default)
			)
			(layer "B.Fab")
		)
		(fp_line
			(start -0.120396 0.3048)
			(end -0.120396 0.2794)
			(stroke
				(width 0.1)
				(type default)
			)
			(layer "B.Fab")
		)
		(fp_line
			(start 0.12065 0.3048)
			(end 0.67945 0.3048)
			(stroke
				(width 0.1)
				(type default)
			)
			(layer "B.Fab")
		)
		(fp_line
			(start 0.67945 0.3048)
			(end 0.67945 -0.305054)
			(stroke
				(width 0.1)
				(type default)
			)
			(layer "B.Fab")
		)
		(fp_line
			(start -0.120396 0.2794)
			(end 0.12065 0.2794)
			(stroke
				(width 0.1)
				(type default)
			)
			(layer "B.Fab")
		)
		(fp_line
			(start 0.12065 0.2794)
			(end 0.12065 0.3048)
			(stroke
				(width 0.1)
				(type default)
			)
			(layer "B.Fab")
		)
		(fp_line
			(start -0.12065 -0.2794)
			(end -0.12065 -0.3048)
			(stroke
				(width 0.1)
				(type default)
			)
			(layer "B.Fab")
		)
		(fp_line
			(start 0.12065 -0.2794)
			(end -0.12065 -0.2794)
			(stroke
				(width 0.1)
				(type default)
			)
			(layer "B.Fab")
		)
		(fp_line
			(start -0.67945 -0.3048)
			(end -0.67945 0.3048)
			(stroke
				(width 0.1)
				(type default)
			)
			(layer "B.Fab")
		)
		(fp_line
			(start -0.12065 -0.3048)
			(end -0.67945 -0.3048)
			(stroke
				(width 0.1)
				(type default)
			)
			(layer "B.Fab")
		)
		(fp_line
			(start 0.12065 -0.305054)
			(end 0.12065 -0.2794)
			(stroke
				(width 0.1)
				(type default)
			)
			(layer "B.Fab")
		)
		(fp_line
			(start 0.67945 -0.305054)
			(end 0.12065 -0.305054)
			(stroke
				(width 0.1)
				(type default)
			)
			(layer "B.Fab")
		)
		(pad "1" smd circle
			(at 0.40005 0 90)
			(size 0 0)
			(layers "B.Cu" "B.Mask" "B.Paste")
			(net "H_CPU0_PROCHOT_LVC1_R_N")
		)
		(pad "2" smd circle
			(at -0.40005 0 90)
			(size 0 0)
			(layers "B.Cu" "B.Mask" "B.Paste")
			(net "H_CPU0_PROCHOT_LVC1_N")
		)
	)
)
